# SCM (Grand Teton) — schematic netlist excerpt (pin names and nets, part order shuffled) for the footprints in the layout excerpt that follows; sources: Cadence DE-HDL packaged netlist, KiCad conversion of 12092022_DA0F0TMDCD0_F0T_Management_Board_D_brd_V3_OCP.brd

R167  Q_RES  330 1% CHIP  pkg 0402LF  page 13 : A = P3V3_AUX ; B = BMC_HEARTBEAT_R_N
R677  Q_RES  10K 1% CHIP  pkg 0402LF  page 51 : A = U56_ADJ_1 ; B = GND

(kicad_pcb
	(version 20260206)
	(generator "pcbnew")
	(generator_version "10.0")
	(general
		(thickness 1.6)
		(legacy_teardrops no)
	)
	(paper "A4")
	(title_block
		(title "12092022_DA0F0TMDCD0_F0T_Management_Board_D_brd_V3_OCP.brd")
		(comment 1 "Grand Teton / footprints 639-640 of 1440")
	)
	(layers
		(0 "F.Cu" signal "TOP")
		(4 "In1.Cu" signal "GND")
		(6 "In2.Cu" signal "IN1")
		(8 "In3.Cu" signal "GND1")
		(10 "In4.Cu" signal "IN2")
		(12 "In5.Cu" signal "VCC")
		(14 "In6.Cu" signal "VCC1")
		(16 "In7.Cu" signal "IN3")
		(18 "In8.Cu" signal "GND2")
		(20 "In9.Cu" signal "IN4")
		(22 "In10.Cu" signal "GND3")
		(2 "B.Cu" signal "BOTTOM")
		(9 "F.Adhes" user "F.Adhesive")
		(11 "B.Adhes" user "B.Adhesive")
		(13 "F.Paste" user "Package Geometry/Pastemask Top")
		(15 "B.Paste" user "Package Geometry/Pastemask Bottom")
		(5 "F.SilkS" user "Ref Des/Silkscreen Top")
		(7 "B.SilkS" user "Ref Des/Silkscreen Bottom")
		(1 "F.Mask" user "Board Geometry/Soldermask Top")
		(3 "B.Mask" user "Board Geometry/Soldermask Bottom")
		(17 "Dwgs.User" user "User.Drawings")
		(19 "Cmts.User" user "User.Comments")
		(21 "Eco1.User" user "User.Eco1")
		(23 "Eco2.User" user "User.Eco2")
		(25 "Edge.Cuts" user "Board Geometry/Outline")
		(27 "Margin" user)
		(31 "F.CrtYd" user "Package Geometry/Place Bound Top")
		(29 "B.CrtYd" user "Package Geometry/Place Bound Bottom")
		(35 "F.Fab" user "Ref Des/Assembly Top")
		(33 "B.Fab" user "Ref Des/Assembly Bottom")
	)
	(footprint ""
		(layer "F.Cu")
		(at 43.9166 -69.2912 180)
		(property "Reference" "R167"
			(at 0 0 180)
			(layer "F.SilkS")
			(hide yes)
			(effects
				(font
					(size 1.27 1.27)
				)
			)
		)
		(property "Value" ""
			(at 0 0 180)
			(layer "F.Fab")
			(effects
				(font
					(size 1.27 1.27)
				)
			)
		)
		(duplicate_pad_numbers_are_jumpers no)
		(fp_line
			(start 0.7874 0.4064)
			(end -0.7874 0.4064)
			(stroke
				(width 0.1524)
				(type default)
			)
			(layer "F.SilkS")
		)
		(fp_line
			(start 0.7874 -0.4064)
			(end 0.7874 0.4064)
			(stroke
				(width 0.1524)
				(type default)
			)
			(layer "F.SilkS")
		)
		(fp_line
			(start -0.7874 0.4064)
			(end -0.7874 -0.4064)
			(stroke
				(width 0.1524)
				(type default)
			)
			(layer "F.SilkS")
		)
		(fp_line
			(start -0.7874 -0.4064)
			(end 0.7874 -0.4064)
			(stroke
				(width 0.1524)
				(type default)
			)
			(layer "F.SilkS")
		)
		(fp_line
			(start 0.67945 0.3048)
			(end 0.120396 0.3048)
			(stroke
				(width 0.1)
				(type default)
			)
			(layer "F.Fab")
		)
		(fp_line
			(start 0.67945 -0.3048)
			(end 0.67945 0.3048)
			(stroke
				(width 0.1)
				(type default)
			)
			(layer "F.Fab")
		)
		(fp_line
			(start 0.12065 -0.2794)
			(end 0.12065 -0.3048)
			(stroke
				(width 0.1)
				(type default)
			)
			(layer "F.Fab")
		)
		(fp_line
			(start 0.12065 -0.3048)
			(end 0.67945 -0.3048)
			(stroke
				(width 0.1)
				(type default)
			)
			(layer "F.Fab")
		)
		(fp_line
			(start 0.120396 0.3048)
			(end 0.120396 0.2794)
			(stroke
				(width 0.1)
				(type default)
			)
			(layer "F.Fab")
		)
		(fp_line
			(start 0.120396 0.2794)
			(end -0.12065 0.2794)
			(stroke
				(width 0.1)
				(type default)
			)
			(layer "F.Fab")
		)
		(fp_line
			(start -0.12065 0.3048)
			(end -0.67945 0.3048)
			(stroke
				(width 0.1)
				(type default)
			)
			(layer "F.Fab")
		)
		(fp_line
			(start -0.12065 0.2794)
			(end -0.12065 0.3048)
			(stroke
				(width 0.1)
				(type default)
			)
			(layer "F.Fab")
		)
		(fp_line
			(start -0.12065 -0.2794)
			(end 0.12065 -0.2794)
			(stroke
				(width 0.1)
				(type default)
			)
			(layer "F.Fab")
		)
		(fp_line
			(start -0.12065 -0.305054)
			(end -0.12065 -0.2794)
			(stroke
				(width 0.1)
				(type default)
			)
			(layer "F.Fab")
		)
		(fp_line
			(start -0.67945 0.3048)
			(end -0.67945 -0.305054)
			(stroke
				(width 0.1)
				(type default)
			)
			(layer "F.Fab")
		)
		(fp_line
			(start -0.67945 -0.305054)
			(end -0.12065 -0.305054)
			(stroke
				(width 0.1)
				(type default)
			)
			(layer "F.Fab")
		)
		(pad "1" smd circle
			(at -0.40005 0 180)
			(size 0 0)
			(layers "F.Cu" "F.Mask" "F.Paste")
			(net "P3V3_AUX")
		)
		(pad "2" smd circle
			(at 0.40005 0 180)
			(size 0 0)
			(layers "F.Cu" "F.Mask" "F.Paste")
			(net "BMC_HEARTBEAT_R_N")
		)
	)
	(footprint ""
		(layer "F.Cu")
		(at 75.946 -77.978)
		(property "Reference" "R677"
			(at 0 0 0)
			(layer "F.SilkS")
			(hide yes)
			(effects
				(font
					(size 1.27 1.27)
				)
			)
		)
		(property "Value" ""
			(at 0 0 0)
			(layer "F.Fab")
			(effects
				(font
					(size 1.27 1.27)
				)
			)
		)
		(duplicate_pad_numbers_are_jumpers no)
		(fp_line
			(start -0.7874 -0.4064)
			(end 0.7874 -0.4064)
			(stroke
				(width 0.1524)
				(type default)
			)
			(layer "F.SilkS")
		)
		(fp_line
			(start -0.7874 0.4064)
			(end -0.7874 -0.4064)
			(stroke
				(width 0.1524)
				(type default)
			)
			(layer "F.SilkS")
		)
		(fp_line
			(start 0.7874 -0.4064)
			(end 0.7874 0.4064)
			(stroke
				(width 0.1524)
				(type default)
			)
			(layer "F.SilkS")
		)
		(fp_line
			(start 0.7874 0.4064)
			(end -0.7874 0.4064)
			(stroke
				(width 0.1524)
				(type default)
			)
			(layer "F.SilkS")
		)
		(fp_line
			(start -0.67945 -0.305054)
			(end -0.12065 -0.305054)
			(stroke
				(width 0.1)
				(type default)
			)
			(layer "F.Fab")
		)
		(fp_line
			(start -0.67945 0.3048)
			(end -0.67945 -0.305054)
			(stroke
				(width 0.1)
				(type default)
			)
			(layer "F.Fab")
		)
		(fp_line
			(start -0.12065 -0.305054)
			(end -0.12065 -0.2794)
			(stroke
				(width 0.1)
				(type default)
			)
			(layer "F.Fab")
		)
		(fp_line
			(start -0.12065 -0.2794)
			(end 0.12065 -0.2794)
			(stroke
				(width 0.1)
				(type default)
			)
			(layer "F.Fab")
		)
		(fp_line
			(start -0.12065 0.2794)
			(end -0.12065 0.3048)
			(stroke
				(width 0.1)
				(type default)
			)
			(layer "F.Fab")
		)
		(fp_line
			(start -0.12065 0.3048)
			(end -0.67945 0.3048)
			(stroke
				(width 0.1)
				(type default)
			)
			(layer "F.Fab")
		)
		(fp_line
			(start 0.120396 0.2794)
			(end -0.12065 0.2794)
			(stroke
				(width 0.1)
				(type default)
			)
			(layer "F.Fab")
		)
		(fp_line
			(start 0.120396 0.3048)
			(end 0.120396 0.2794)
			(stroke
				(width 0.1)
				(type default)
			)
			(layer "F.Fab")
		)
		(fp_line
			(start 0.12065 -0.3048)
			(end 0.67945 -0.3048)
			(stroke
				(width 0.1)
				(type default)
			)
			(layer "F.Fab")
		)
		(fp_line
			(start 0.12065 -0.2794)
			(end 0.12065 -0.3048)
			(stroke
				(width 0.1)
				(type default)
			)
			(layer "F.Fab")
		)
		(fp_line
			(start 0.67945 -0.3048)
			(end 0.67945 0.3048)
			(stroke
				(width 0.1)
				(type default)
			)
			(layer "F.Fab")
		)
		(fp_line
			(start 0.67945 0.3048)
			(end 0.120396 0.3048)
			(stroke
				(width 0.1)
				(type default)
			)
			(layer "F.Fab")
		)
		(pad "1" smd circle
			(at -0.40005 0)
			(size 0 0)
			(layers "F.Cu" "F.Mask" "F.Paste")
			(net "U56_ADJ_1")
		)
		(pad "2" smd circle
			(at 0.40005 0)
			(size 0 0)
			(layers "F.Cu" "F.Mask" "F.Paste")
			(net "GND")
		)
	)
)
